FILE_TYPE = CONNECTIVITY;
{Allegro Design Entry HDL 17.4-2019 S026 (4007227) 1/17/2022}
"PAGE_NUMBER" = 415;
0"NC";
1"P5E_CPU0_P2_TX_C_DP<15:8>";
2"P5E_CPU0_P2_TX_C_DN<15:8>";
3"P5E_CPU0_P2_TX_C_DN<7:0>";
4"P5E_CPU0_P2_TX_C_DP<7:0>";
5"P5E_CPU0_P2_TX_C_DN<12>";
6"P5E_CPU0_P2_TX_C_DP<11>";
7"P5E_CPU0_P2_TX_C_DN<10>";
8"P5E_CPU0_P2_TX_C_DP<9>";
9"P5E_CPU0_P2_TX_C_DN<9>";
10"P5E_CPU0_P2_TX_C_DP<10>";
11"P5E_CPU0_P2_TX_C_DN<11>";
12"P5E_CPU0_P2_TX_C_DP<12>";
13"P5E_CPU0_P2_TX_C_DP<13>";
14"P5E_CPU0_P2_TX_C_DP<14>";
15"P5E_CPU0_P2_TX_C_DN<14>";
16"P5E_CPU0_P2_TX_C_DP<15>";
17"P5E_CPU0_P2_TX_C_DP<6>";
18"P5E_CPU0_P2_TX_C_DN<6>";
19"P5E_CPU0_P2_TX_C_DN<2>";
20"P5E_CPU0_P2_TX_C_DP<2>";
21"P5E_CPU0_P2_TX_C_DN<15>";
22"P5E_CPU0_P2_TX_C_DN<5>";
23"P5E_CPU0_P2_TX_C_DP<7>";
24"P5E_CPU0_P2_TX_C_DP<5>";
25"P5E_CPU0_P2_TX_C_DP<4>";
26"P5E_CPU0_P2_TX_C_DN<1>";
27"P5E_CPU0_P2_TX_C_DP<1>";
28"P5E_CPU0_P2_TX_C_DN<0>";
29"P5E_CPU0_P2_TX_C_DP<0>";
30"P5E_CPU0_P2_TX_C_DN<13>";
31"P5E_CPU0_P2_TX_C_DN<3>";
32"P5E_CPU0_P2_TX_C_DP<3>";
33"P5E_CPU0_P2_TX_C_DN<7>";
34"P5E_CPU0_P2_TX_C_DN<4>";
35"P5E_CPU0_P2_TX_C_DN<8>";
36"P5E_CPU0_P2_TX_C_DP<8>";
%"TAP"
"1","(-6750,2525)","0","standard","I1";
;
CDS_LIB"standard"
BODY_TYPE"PLUMBING"
HDL_TAP"TRUE";
"B \NAC \NWC"1;
"S \NAC"
BN"8"36;
%"TAP"
"1","(-6950,4025)","0","standard","I10";
;
CDS_LIB"standard"
BODY_TYPE"PLUMBING"
HDL_TAP"TRUE";
"B \NAC \NWC"2;
"S \NAC"
BN"12"5;
%"TAP"
"1","(-6750,4275)","0","standard","I11";
;
CDS_LIB"standard"
BODY_TYPE"PLUMBING"
HDL_TAP"TRUE";
"B \NAC \NWC"1;
"S \NAC"
BN"13"13;
%"TAP"
"1","(-6950,4375)","0","standard","I12";
;
CDS_LIB"standard"
BODY_TYPE"PLUMBING"
HDL_TAP"TRUE";
"B \NAC \NWC"2;
"S \NAC"
BN"13"30;
%"TAP"
"1","(-6750,4625)","0","standard","I13";
;
CDS_LIB"standard"
BODY_TYPE"PLUMBING"
HDL_TAP"TRUE";
"B \NAC \NWC"1;
"S \NAC"
BN"14"14;
%"TAP"
"1","(-6950,4725)","0","standard","I14";
;
CDS_LIB"standard"
BODY_TYPE"PLUMBING"
HDL_TAP"TRUE";
"B \NAC \NWC"2;
"S \NAC"
BN"14"15;
%"TAP"
"1","(-6750,4975)","0","standard","I15";
;
CDS_LIB"standard"
BODY_TYPE"PLUMBING"
HDL_TAP"TRUE";
"B \NAC \NWC"1;
"S \NAC"
BN"15"16;
%"TAP"
"1","(-6950,5075)","0","standard","I16";
;
CDS_LIB"standard"
BODY_TYPE"PLUMBING"
HDL_TAP"TRUE";
"B \NAC \NWC"2;
"S \NAC"
BN"15"21;
%"TAP"
"1","(-2125,2475)","0","standard","I19";
;
CDS_LIB"standard"
BODY_TYPE"PLUMBING"
HDL_TAP"TRUE";
"B \NAC \NWC"4;
"S \NAC"
BN"0"29;
%"TAP"
"1","(-6950,2625)","0","standard","I2";
;
CDS_LIB"standard"
BODY_TYPE"PLUMBING"
HDL_TAP"TRUE";
"B \NAC \NWC"2;
"S \NAC"
BN"8"35;
%"TAP"
"1","(-2325,2575)","0","standard","I20";
;
CDS_LIB"standard"
BODY_TYPE"PLUMBING"
HDL_TAP"TRUE";
"B \NAC \NWC"3;
"S \NAC"
BN"0"28;
%"TAP"
"1","(-2325,2825)","0","standard","I21";
;
CDS_LIB"standard"
BODY_TYPE"PLUMBING"
HDL_TAP"TRUE";
"B \NAC \NWC"3;
"S \NAC"
BN"1"26;
%"TAP"
"1","(-2125,2925)","0","standard","I22";
;
CDS_LIB"standard"
BODY_TYPE"PLUMBING"
HDL_TAP"TRUE";
"B \NAC \NWC"4;
"S \NAC"
BN"1"27;
%"TAP"
"1","(-2325,3275)","0","standard","I23";
;
CDS_LIB"standard"
BODY_TYPE"PLUMBING"
HDL_TAP"TRUE";
"B \NAC \NWC"3;
"S \NAC"
BN"2"19;
%"TAP"
"1","(-2125,3175)","0","standard","I24";
;
CDS_LIB"standard"
BODY_TYPE"PLUMBING"
HDL_TAP"TRUE";
"B \NAC \NWC"4;
"S \NAC"
BN"2"20;
%"TAP"
"1","(-2325,3625)","0","standard","I25";
;
CDS_LIB"standard"
BODY_TYPE"PLUMBING"
HDL_TAP"TRUE";
"B \NAC \NWC"3;
"S \NAC"
BN"3"31;
%"TAP"
"1","(-2125,3525)","0","standard","I26";
;
CDS_LIB"standard"
BODY_TYPE"PLUMBING"
HDL_TAP"TRUE";
"B \NAC \NWC"4;
"S \NAC"
BN"3"32;
%"TAP"
"1","(-2325,3975)","0","standard","I27";
;
CDS_LIB"standard"
BODY_TYPE"PLUMBING"
HDL_TAP"TRUE";
"B \NAC \NWC"3;
"S \NAC"
BN"4"34;
%"TAP"
"1","(-2125,3875)","0","standard","I28";
;
CDS_LIB"standard"
BODY_TYPE"PLUMBING"
HDL_TAP"TRUE";
"B \NAC \NWC"4;
"S \NAC"
BN"4"25;
%"TAP"
"1","(-2125,4225)","0","standard","I29";
;
CDS_LIB"standard"
BODY_TYPE"PLUMBING"
HDL_TAP"TRUE";
"B \NAC \NWC"4;
"S \NAC"
BN"5"24;
%"TAP"
"1","(-6750,2875)","0","standard","I3";
;
CDS_LIB"standard"
BODY_TYPE"PLUMBING"
HDL_TAP"TRUE";
"B \NAC \NWC"1;
"S \NAC"
BN"9"8;
%"TAP"
"1","(-2325,4325)","0","standard","I30";
;
CDS_LIB"standard"
BODY_TYPE"PLUMBING"
HDL_TAP"TRUE";
"B \NAC \NWC"3;
"S \NAC"
BN"5"22;
%"TAP"
"1","(-2325,4675)","0","standard","I31";
;
CDS_LIB"standard"
BODY_TYPE"PLUMBING"
HDL_TAP"TRUE";
"B \NAC \NWC"3;
"S \NAC"
BN"6"18;
%"TAP"
"1","(-2125,4575)","0","standard","I32";
;
CDS_LIB"standard"
BODY_TYPE"PLUMBING"
HDL_TAP"TRUE";
"B \NAC \NWC"4;
"S \NAC"
BN"6"17;
%"TAP"
"1","(-2325,5025)","0","standard","I33";
;
CDS_LIB"standard"
BODY_TYPE"PLUMBING"
HDL_TAP"TRUE";
"B \NAC \NWC"3;
"S \NAC"
BN"7"33;
%"TAP"
"1","(-2125,4925)","0","standard","I34";
;
CDS_LIB"standard"
BODY_TYPE"PLUMBING"
HDL_TAP"TRUE";
"B \NAC \NWC"4;
"S \NAC"
BN"7"23;
%"PT5161LRS"
"9","(-3350,3775)","0","pure_quanta","I37";
;
LOCATION"U6012"
$SEC"9"
CDS_SEC"9"
MATERIAL"IC"
PART_TYPE"SMLF"
VALUE"PT5161LRS"
NEEDS_NO_SIZE"TRUE"
CDS_LMAN_SYM_OUTLINE"-350,1450,300,-1400"
CDS_LIB"pure_quanta"
PART_NUMBER"AJ051610U03";
"B_PERN15"
$PN"EY35"29;
"B_PERP15"
$PN"EV34"28;
"B_PERN14"
$PN"EN35"26;
"B_PERP14"
$PN"EL34"27;
"B_PERN13"
$PN"EF35"20;
"B_PERP13"
$PN"ED34"19;
"B_PERN12"
$PN"DW35"32;
"B_PERP12"
$PN"DU34"31;
"B_PERN11"
$PN"DM35"25;
"B_PERP11"
$PN"DK34"34;
"B_PERN10"
$PN"DE35"24;
"B_PERP10"
$PN"DC34"22;
"B_PERN9"
$PN"CV35"17;
"B_PERP9"
$PN"CT34"18;
"B_PERN8"
$PN"CL35"23;
"B_PERP8"
$PN"CJ34"33;
%"PT5161LRS"
"8","(-7975,3825)","0","pure_quanta","I38";
;
LOCATION"U6012"
$SEC"8"
CDS_SEC"8"
PART_TYPE"SMLF"
VALUE"PT5161LRS"
MATERIAL"IC"
CDS_LIB"pure_quanta"
CDS_LMAN_SYM_OUTLINE"-350,1450,300,-1400"
NEEDS_NO_SIZE"TRUE"
PART_NUMBER"AJ051610U03";
"B_PERN7"
$PN"CD35"36;
"B_PERP7"
$PN"CB34"35;
"B_PERN6"
$PN"BU35"8;
"B_PERP6"
$PN"BR34"9;
"B_PERN5"
$PN"BK35"10;
"B_PERP5"
$PN"BH34"7;
"B_PERN4"
$PN"BC35"6;
"B_PERP4"
$PN"BA34"11;
"B_PERN3"
$PN"AT35"12;
"B_PERP3"
$PN"AP34"5;
"B_PERN2"
$PN"AJ35"13;
"B_PERP2"
$PN"AG34"30;
"B_PERN1"
$PN"AB35"14;
"B_PERP1"
$PN"Y34"15;
"B_PERN0"
$PN"R35"16;
"B_PERP0"
$PN"N34"21;
%"TAP"
"1","(-6950,2975)","0","standard","I4";
;
CDS_LIB"standard"
BODY_TYPE"PLUMBING"
HDL_TAP"TRUE";
"B \NAC \NWC"2;
"S \NAC"
BN"9"9;
%"TAP"
"1","(-6750,3225)","0","standard","I5";
;
CDS_LIB"standard"
BODY_TYPE"PLUMBING"
HDL_TAP"TRUE";
"B \NAC \NWC"1;
"S \NAC"
BN"10"10;
%"TAP"
"1","(-6950,3325)","0","standard","I6";
;
CDS_LIB"standard"
BODY_TYPE"PLUMBING"
HDL_TAP"TRUE";
"B \NAC \NWC"2;
"S \NAC"
BN"10"7;
%"TAP"
"1","(-6750,3575)","0","standard","I7";
;
CDS_LIB"standard"
BODY_TYPE"PLUMBING"
HDL_TAP"TRUE";
"B \NAC \NWC"1;
"S \NAC"
BN"11"6;
%"TAP"
"1","(-6950,3675)","0","standard","I8";
;
CDS_LIB"standard"
BODY_TYPE"PLUMBING"
HDL_TAP"TRUE";
"B \NAC \NWC"2;
"S \NAC"
BN"11"11;
%"TAP"
"1","(-6750,3925)","0","standard","I9";
;
CDS_LIB"standard"
BODY_TYPE"PLUMBING"
HDL_TAP"TRUE";
"B \NAC \NWC"1;
"S \NAC"
BN"12"12;
END.
